# T6G (Grand Teton) — schematic netlist excerpt (pin names and nets, part order shuffled) for the footprints in the layout excerpt that follows; sources: Cadence DE-HDL packaged netlist, KiCad conversion of 04192023_DAF0TMB3IC0_F0TG_MB_C_brd_V02_OCP.brd

C836  Q_CAP_DIFFBUS  DIFF BUS_0.22UF 6.3V 20% X6S  pkg C0201  page 65 : \1\ = P5E_CPU1_P0_TX_C_DN<0> ; \2\ = P5E_CPU1_P0_TX_DN<0>
R8298  Q_RES  1K 1% CHIP  pkg 0402LF  page 193 : A = P3V3_AUX ; B = PWRGD_PVDDCR_SOC_P0_R
C49  Q_CAP_DIFFBUS  DIFF BUS_0.22UF 6.3V 20% X6S  pkg C0201  page 67 : \1\ = P5E_CPU1_P3_TX_C_DP<15> ; \2\ = P5E_CPU1_P3_TX_DP<15>
C6513  Q_CAP_DIFFBUS  DIFF BUS_0.22UF 6.3V 20% X6S  pkg C0201  page 275 : \1\ = P5E_CPU0_P0_TX_BUF_C_DP<6> ; \2\ = P5E_CPU0_P0_TX_BUF_DP<6>

(kicad_pcb
	(version 20260206)
	(generator "pcbnew")
	(generator_version "10.0")
	(general
		(thickness 1.6)
		(legacy_teardrops no)
	)
	(paper "A4")
	(title_block
		(title "04192023_DAF0TMB3IC0_F0TG_MB_C_brd_V02_OCP.brd")
		(comment 1 "Grand Teton / footprints 3304-3307 of 8354")
	)
	(layers
		(0 "F.Cu" signal "TOP")
		(4 "In1.Cu" signal "GND")
		(6 "In2.Cu" signal "IN1")
		(8 "In3.Cu" signal "GND1")
		(10 "In4.Cu" signal "IN2")
		(12 "In5.Cu" signal "GND2")
		(14 "In6.Cu" signal "IN3")
		(16 "In7.Cu" signal "GND3")
		(18 "In8.Cu" signal "VCC")
		(20 "In9.Cu" signal "VCC1")
		(22 "In10.Cu" signal "GND4")
		(24 "In11.Cu" signal "IN4")
		(26 "In12.Cu" signal "GND5")
		(28 "In13.Cu" signal "IN5")
		(30 "In14.Cu" signal "GND6")
		(32 "In15.Cu" signal "IN6")
		(34 "In16.Cu" signal "GND7")
		(2 "B.Cu" signal "BOTTOM")
		(9 "F.Adhes" user "F.Adhesive")
		(11 "B.Adhes" user "B.Adhesive")
		(13 "F.Paste" user "Package Geometry/Pastemask Top")
		(15 "B.Paste" user "Package Geometry/Pastemask Bottom")
		(5 "F.SilkS" user "Ref Des/Silkscreen Top")
		(7 "B.SilkS" user "Ref Des/Silkscreen Bottom")
		(1 "F.Mask" user "Board Geometry/Soldermask Top")
		(3 "B.Mask" user "Board Geometry/Soldermask Bottom")
		(17 "Dwgs.User" user "User.Drawings")
		(19 "Cmts.User" user "User.Comments")
		(21 "Eco1.User" user "User.Eco1")
		(23 "Eco2.User" user "User.Eco2")
		(25 "Edge.Cuts" user "Board Geometry/Outline")
		(27 "Margin" user)
		(31 "F.CrtYd" user "Package Geometry/Place Bound Top")
		(29 "B.CrtYd" user "Package Geometry/Place Bound Bottom")
		(35 "F.Fab" user "Ref Des/Assembly Top")
		(33 "B.Fab" user "Ref Des/Assembly Bottom")
	)
	(footprint ""
		(layer "F.Cu")
		(at 136.840976 -379.471428)
		(property "Reference" "C49"
			(at 0 0 0)
			(layer "F.SilkS")
			(hide yes)
			(effects
				(font
					(size 1.27 1.27)
				)
			)
		)
		(property "Value" ""
			(at 0 0 0)
			(layer "F.Fab")
			(effects
				(font
					(size 1.27 1.27)
				)
			)
		)
		(duplicate_pad_numbers_are_jumpers no)
		(fp_line
			(start -0.299974 -0.150114)
			(end 0.299974 -0.150114)
			(stroke
				(width 0.1)
				(type default)
			)
			(layer "F.Fab")
		)
		(fp_line
			(start -0.299974 0.150114)
			(end -0.299974 -0.150114)
			(stroke
				(width 0.1)
				(type default)
			)
			(layer "F.Fab")
		)
		(fp_line
			(start 0.299974 -0.150114)
			(end 0.299974 0.150114)
			(stroke
				(width 0.1)
				(type default)
			)
			(layer "F.Fab")
		)
		(fp_line
			(start 0.299974 0.150114)
			(end -0.299974 0.150114)
			(stroke
				(width 0.1)
				(type default)
			)
			(layer "F.Fab")
		)
		(pad "1" smd rect
			(at -0.2667 0)
			(size 0.3048 0.381)
			(layers "F.Cu" "F.Mask" "F.Paste")
			(net "P5E_CPU1_P3_TX_C_DP<15>")
		)
		(pad "2" smd rect
			(at 0.2667 0)
			(size 0.3048 0.381)
			(layers "F.Cu" "F.Mask" "F.Paste")
			(net "P5E_CPU1_P3_TX_DP<15>")
		)
	)
	(footprint ""
		(layer "F.Cu")
		(at 372.937278 -142.488158)
		(property "Reference" "R8298"
			(at 0 0 0)
			(layer "F.SilkS")
			(hide yes)
			(effects
				(font
					(size 1.27 1.27)
				)
			)
		)
		(property "Value" ""
			(at 0 0 0)
			(layer "F.Fab")
			(effects
				(font
					(size 1.27 1.27)
				)
			)
		)
		(duplicate_pad_numbers_are_jumpers no)
		(fp_line
			(start -0.7874 -0.4064)
			(end 0.7874 -0.4064)
			(stroke
				(width 0.1524)
				(type default)
			)
			(layer "F.SilkS")
		)
		(fp_line
			(start -0.7874 0.4064)
			(end -0.7874 -0.4064)
			(stroke
				(width 0.1524)
				(type default)
			)
			(layer "F.SilkS")
		)
		(fp_line
			(start 0.7874 -0.4064)
			(end 0.7874 0.4064)
			(stroke
				(width 0.1524)
				(type default)
			)
			(layer "F.SilkS")
		)
		(fp_line
			(start 0.7874 0.4064)
			(end -0.7874 0.4064)
			(stroke
				(width 0.1524)
				(type default)
			)
			(layer "F.SilkS")
		)
		(fp_line
			(start -0.67945 -0.305054)
			(end -0.12065 -0.305054)
			(stroke
				(width 0.1)
				(type default)
			)
			(layer "F.Fab")
		)
		(fp_line
			(start -0.67945 0.3048)
			(end -0.67945 -0.305054)
			(stroke
				(width 0.1)
				(type default)
			)
			(layer "F.Fab")
		)
		(fp_line
			(start -0.12065 -0.305054)
			(end -0.12065 -0.2794)
			(stroke
				(width 0.1)
				(type default)
			)
			(layer "F.Fab")
		)
		(fp_line
			(start -0.12065 -0.2794)
			(end 0.12065 -0.2794)
			(stroke
				(width 0.1)
				(type default)
			)
			(layer "F.Fab")
		)
		(fp_line
			(start -0.12065 0.2794)
			(end -0.12065 0.3048)
			(stroke
				(width 0.1)
				(type default)
			)
			(layer "F.Fab")
		)
		(fp_line
			(start -0.12065 0.3048)
			(end -0.67945 0.3048)
			(stroke
				(width 0.1)
				(type default)
			)
			(layer "F.Fab")
		)
		(fp_line
			(start 0.120396 0.2794)
			(end -0.12065 0.2794)
			(stroke
				(width 0.1)
				(type default)
			)
			(layer "F.Fab")
		)
		(fp_line
			(start 0.120396 0.3048)
			(end 0.120396 0.2794)
			(stroke
				(width 0.1)
				(type default)
			)
			(layer "F.Fab")
		)
		(fp_line
			(start 0.12065 -0.3048)
			(end 0.67945 -0.3048)
			(stroke
				(width 0.1)
				(type default)
			)
			(layer "F.Fab")
		)
		(fp_line
			(start 0.12065 -0.2794)
			(end 0.12065 -0.3048)
			(stroke
				(width 0.1)
				(type default)
			)
			(layer "F.Fab")
		)
		(fp_line
			(start 0.67945 -0.3048)
			(end 0.67945 0.3048)
			(stroke
				(width 0.1)
				(type default)
			)
			(layer "F.Fab")
		)
		(fp_line
			(start 0.67945 0.3048)
			(end 0.120396 0.3048)
			(stroke
				(width 0.1)
				(type default)
			)
			(layer "F.Fab")
		)
		(pad "1" smd circle
			(at -0.40005 0)
			(size 0 0)
			(layers "F.Cu" "F.Mask" "F.Paste")
			(net "P3V3_AUX")
		)
		(pad "2" smd circle
			(at 0.40005 0)
			(size 0 0)
			(layers "F.Cu" "F.Mask" "F.Paste")
			(net "PWRGD_PVDDCR_SOC_P0_R")
		)
	)
	(footprint ""
		(layer "F.Cu")
		(at 42.967402 -381.48006 180)
		(property "Reference" "C836"
			(at 0 0 180)
			(layer "F.SilkS")
			(hide yes)
			(effects
				(font
					(size 1.27 1.27)
				)
			)
		)
		(property "Value" ""
			(at 0 0 180)
			(layer "F.Fab")
			(effects
				(font
					(size 1.27 1.27)
				)
			)
		)
		(duplicate_pad_numbers_are_jumpers no)
		(fp_line
			(start 0.299974 0.150114)
			(end -0.299974 0.150114)
			(stroke
				(width 0.1)
				(type default)
			)
			(layer "F.Fab")
		)
		(fp_line
			(start 0.299974 -0.150114)
			(end 0.299974 0.150114)
			(stroke
				(width 0.1)
				(type default)
			)
			(layer "F.Fab")
		)
		(fp_line
			(start -0.299974 0.150114)
			(end -0.299974 -0.150114)
			(stroke
				(width 0.1)
				(type default)
			)
			(layer "F.Fab")
		)
		(fp_line
			(start -0.299974 -0.150114)
			(end 0.299974 -0.150114)
			(stroke
				(width 0.1)
				(type default)
			)
			(layer "F.Fab")
		)
		(pad "1" smd rect
			(at -0.2667 0 180)
			(size 0.3048 0.381)
			(layers "F.Cu" "F.Mask" "F.Paste")
			(net "P5E_CPU1_P0_TX_C_DN<0>")
		)
		(pad "2" smd rect
			(at 0.2667 0 180)
			(size 0.3048 0.381)
			(layers "F.Cu" "F.Mask" "F.Paste")
			(net "P5E_CPU1_P0_TX_DN<0>")
		)
	)
	(footprint ""
		(layer "F.Cu")
		(at 323.062346 -416.899344 -90)
		(property "Reference" "C6513"
			(at 0 0 270)
			(layer "F.SilkS")
			(hide yes)
			(effects
				(font
					(size 1.27 1.27)
				)
			)
		)
		(property "Value" ""
			(at 0 0 270)
			(layer "F.Fab")
			(effects
				(font
					(size 1.27 1.27)
				)
			)
		)
		(duplicate_pad_numbers_are_jumpers no)
		(fp_line
			(start -0.299974 0.150114)
			(end -0.299974 -0.150114)
			(stroke
				(width 0.1)
				(type default)
			)
			(layer "F.Fab")
		)
		(fp_line
			(start 0.299974 0.150114)
			(end -0.299974 0.150114)
			(stroke
				(width 0.1)
				(type default)
			)
			(layer "F.Fab")
		)
		(fp_line
			(start -0.299974 -0.150114)
			(end 0.299974 -0.150114)
			(stroke
				(width 0.1)
				(type default)
			)
			(layer "F.Fab")
		)
		(fp_line
			(start 0.299974 -0.150114)
			(end 0.299974 0.150114)
			(stroke
				(width 0.1)
				(type default)
			)
			(layer "F.Fab")
		)
		(pad "1" smd rect
			(at -0.2667 0 270)
			(size 0.3048 0.381)
			(layers "F.Cu" "F.Mask" "F.Paste")
			(net "P5E_CPU0_P0_TX_BUF_C_DP<6>")
		)
		(pad "2" smd rect
			(at 0.2667 0 270)
			(size 0.3048 0.381)
			(layers "F.Cu" "F.Mask" "F.Paste")
			(net "P5E_CPU0_P0_TX_BUF_DP<6>")
		)
	)
)
